(kicad_pcb
	(version 20260206)
	(generator "pcbnew")
	(generator_version "10.0")
	(general
		(thickness 1.6)
		(legacy_teardrops no)
	)
	(paper "A4")
	(title_block
		(title "v1-tray-backplane — T6M_tray_BP_c_1023_1120.brd")
		(comment 1 "Open CloudServer (Microsoft) / footprints 140-148 of 170")
	)
	(layers
		(0 "F.Cu" signal "TOP")
		(4 "In1.Cu" signal "GND")
		(6 "In2.Cu" signal "IN1")
		(8 "In3.Cu" signal "VCC")
		(10 "In4.Cu" signal "VCC1")
		(12 "In5.Cu" signal "IN2")
		(14 "In6.Cu" signal "GND1")
		(2 "B.Cu" signal "BOTTOM")
		(9 "F.Adhes" user "F.Adhesive")
		(11 "B.Adhes" user "B.Adhesive")
		(13 "F.Paste" user "Package Geometry/Pastemask Top")
		(15 "B.Paste" user "Package Geometry/Pastemask Bottom")
		(5 "F.SilkS" user "Ref Des/Silkscreen Top")
		(7 "B.SilkS" user "Ref Des/Silkscreen Bottom")
		(1 "F.Mask" user "Board Geometry/Soldermask Top")
		(3 "B.Mask" user "Board Geometry/Soldermask Bottom")
		(17 "Dwgs.User" user "User.Drawings")
		(19 "Cmts.User" user "User.Comments")
		(21 "Eco1.User" user "User.Eco1")
		(23 "Eco2.User" user "User.Eco2")
		(25 "Edge.Cuts" user "Board Geometry/Outline")
		(27 "Margin" user)
		(31 "F.CrtYd" user "Package Geometry/Place Bound Top")
		(29 "B.CrtYd" user "Package Geometry/Place Bound Bottom")
		(35 "F.Fab" user "Ref Des/Assembly Top")
		(33 "B.Fab" user "Ref Des/Assembly Bottom")
	)
	(footprint ""
		(layer "F.Cu")
		(at 326.644 -2.6416 90)
		(property "Reference" "C27"
			(at -1.6002 -4.384548 90)
			(unlocked yes)
			(layer "F.SilkS")
			(effects
				(font
					(size 0.7874 0.5842)
					(thickness 0.1524)
				)
				(justify left)
			)
		)
		(property "Value" ""
			(at 0 0 90)
			(layer "F.Fab")
			(effects
				(font
					(size 1.27 1.27)
				)
			)
		)
		(duplicate_pad_numbers_are_jumpers no)
		(fp_line
			(start 0.7874 -0.4064)
			(end 0.7874 0.4064)
			(stroke
				(width 0.1524)
				(type default)
			)
			(layer "F.SilkS")
		)
		(fp_line
			(start -0.7874 -0.4064)
			(end 0.7874 -0.4064)
			(stroke
				(width 0.1524)
				(type default)
			)
			(layer "F.SilkS")
		)
		(fp_line
			(start 0 0.381)
			(end 0 -0.381)
			(stroke
				(width 0.1524)
				(type default)
			)
			(layer "F.SilkS")
		)
		(fp_line
			(start 0.7874 0.4064)
			(end -0.7874 0.4064)
			(stroke
				(width 0.1524)
				(type default)
			)
			(layer "F.SilkS")
		)
		(fp_line
			(start -0.7874 0.4064)
			(end -0.7874 -0.4064)
			(stroke
				(width 0.1524)
				(type default)
			)
			(layer "F.SilkS")
		)
		(fp_poly
			(pts
				(xy -0.5334 0.254) (xy -0.635 0.254) (xy -0.635 0.2286) (xy -0.635 -0.254) (xy -0.5334 -0.254) (xy -0.5334 -0.2794)
				(xy 0.5334 -0.2794) (xy 0.5334 -0.254) (xy 0.635 -0.254) (xy 0.635 0.254) (xy 0.5334 0.254) (xy 0.5334 0.2794)
				(xy -0.508 0.2794) (xy -0.5334 0.2794)
			)
			(stroke
				(width 0)
				(type default)
			)
			(fill no)
			(layer "F.CrtYd")
		)
		(pad "1" smd rect
			(at 0.40005 0 90)
			(size 0.4572 0.508)
			(layers "F.Cu" "F.Mask" "F.Paste")
			(net "P3V3_10G_4_VCCT")
		)
		(pad "2" smd rect
			(at -0.40005 0 90)
			(size 0.4572 0.508)
			(layers "F.Cu" "F.Mask" "F.Paste")
			(net "GND")
		)
	)
	(footprint ""
		(layer "F.Cu")
		(at 340.261448 -22.239732 180)
		(property "Reference" "R72"
			(at 58.070496 4.329684 0)
			(unlocked yes)
			(layer "F.SilkS")
			(effects
				(font
					(size 0.7874 0.5842)
					(thickness 0.1524)
				)
				(justify left)
			)
		)
		(property "Value" ""
			(at 0 0 180)
			(layer "F.Fab")
			(effects
				(font
					(size 1.27 1.27)
				)
			)
		)
		(duplicate_pad_numbers_are_jumpers no)
		(fp_line
			(start 0.7874 0.4064)
			(end -0.7874 0.4064)
			(stroke
				(width 0.1524)
				(type default)
			)
			(layer "F.SilkS")
		)
		(fp_line
			(start 0.7874 -0.4064)
			(end 0.7874 0.4064)
			(stroke
				(width 0.1524)
				(type default)
			)
			(layer "F.SilkS")
		)
		(fp_line
			(start -0.7874 0.4064)
			(end -0.7874 -0.4064)
			(stroke
				(width 0.1524)
				(type default)
			)
			(layer "F.SilkS")
		)
		(fp_line
			(start -0.7874 -0.4064)
			(end 0.7874 -0.4064)
			(stroke
				(width 0.1524)
				(type default)
			)
			(layer "F.SilkS")
		)
		(fp_poly
			(pts
				(xy -0.508 0.2794) (xy -0.508 0.2286) (xy -0.635 0.2286) (xy -0.635 -0.254) (xy -0.5334 -0.254)
				(xy -0.5334 -0.2794) (xy 0.5334 -0.2794) (xy 0.5334 -0.254) (xy 0.635 -0.254) (xy 0.635 0.254) (xy 0.5334 0.254)
				(xy 0.5334 0.2794)
			)
			(stroke
				(width 0)
				(type default)
			)
			(fill no)
			(layer "F.CrtYd")
		)
		(pad "1" smd rect
			(at 0.40005 0 180)
			(size 0.4572 0.508)
			(layers "F.Cu" "F.Mask" "F.Paste")
			(net "ENET10G_4_LOS")
		)
		(pad "2" smd rect
			(at -0.40005 0 180)
			(size 0.4572 0.508)
			(layers "F.Cu" "F.Mask" "F.Paste")
			(net "SFP4_PRESENT_N")
		)
	)
	(footprint ""
		(layer "F.Cu")
		(at 309.200296 -23.520146 -90)
		(property "Reference" "C10"
			(at -2.235708 5.167122 90)
			(unlocked yes)
			(layer "F.SilkS")
			(effects
				(font
					(size 0.7874 0.5842)
					(thickness 0.1524)
				)
			)
		)
		(property "Value" ""
			(at 0 0 270)
			(layer "F.Fab")
			(effects
				(font
					(size 1.27 1.27)
				)
			)
		)
		(duplicate_pad_numbers_are_jumpers no)
		(fp_line
			(start -1.2954 0.5842)
			(end -1.2954 -0.5842)
			(stroke
				(width 0.1524)
				(type default)
			)
			(layer "F.SilkS")
		)
		(fp_line
			(start 1.2954 0.5842)
			(end -1.2954 0.5842)
			(stroke
				(width 0.1524)
				(type default)
			)
			(layer "F.SilkS")
		)
		(fp_line
			(start -1.2954 -0.5842)
			(end 1.2954 -0.5842)
			(stroke
				(width 0.1524)
				(type default)
			)
			(layer "F.SilkS")
		)
		(fp_line
			(start 0 -0.5842)
			(end 0 0.5842)
			(stroke
				(width 0.1524)
				(type default)
			)
			(layer "F.SilkS")
		)
		(fp_line
			(start 1.2954 -0.5842)
			(end 1.2954 0.5842)
			(stroke
				(width 0.1524)
				(type default)
			)
			(layer "F.SilkS")
		)
		(fp_poly
			(pts
				(xy 0.8636 -0.4572) (xy 0.8636 -0.3556) (xy 1.143 -0.3556) (xy 1.143 0.3556) (xy 0.8636 0.3556)
				(xy 0.8636 0.4572) (xy -0.8636 0.4572) (xy -0.8636 0.3556) (xy -1.143 0.3556) (xy -1.143 -0.3556)
				(xy -0.8636 -0.3556) (xy -0.8636 -0.4572)
			)
			(stroke
				(width 0)
				(type default)
			)
			(fill no)
			(layer "F.CrtYd")
		)
		(fp_line
			(start -0.884936 0.504952)
			(end -0.884936 -0.504952)
			(stroke
				(width 0.1)
				(type default)
			)
			(layer "F.Fab")
		)
		(fp_line
			(start 0.884936 0.504952)
			(end -0.884936 0.504952)
			(stroke
				(width 0.1)
				(type default)
			)
			(layer "F.Fab")
		)
		(fp_line
			(start -0.884936 -0.504952)
			(end 0.884936 -0.504952)
			(stroke
				(width 0.1)
				(type default)
			)
			(layer "F.Fab")
		)
		(fp_line
			(start 0.884936 -0.504952)
			(end 0.884936 0.504952)
			(stroke
				(width 0.1)
				(type default)
			)
			(layer "F.Fab")
		)
		(pad "1" smd rect
			(at 0.7366 0)
			(size 0.7112 0.8128)
			(layers "F.Cu" "F.Mask" "F.Paste")
			(net "P12V")
		)
		(pad "2" smd rect
			(at -0.7366 0)
			(size 0.7112 0.8128)
			(layers "F.Cu" "F.Mask" "F.Paste")
			(net "GND")
		)
	)
	(footprint ""
		(layer "F.Cu")
		(at 347.639132 -21.657818 -90)
		(property "Reference" "R65"
			(at -3.3528 57.161684 90)
			(unlocked yes)
			(layer "F.SilkS")
			(effects
				(font
					(size 0.7874 0.5842)
					(thickness 0.1524)
				)
				(justify left)
			)
		)
		(property "Value" ""
			(at 0 0 270)
			(layer "F.Fab")
			(effects
				(font
					(size 1.27 1.27)
				)
			)
		)
		(duplicate_pad_numbers_are_jumpers no)
		(fp_line
			(start -0.7874 0.4064)
			(end -0.7874 -0.4064)
			(stroke
				(width 0.1524)
				(type default)
			)
			(layer "F.SilkS")
		)
		(fp_line
			(start 0.7874 0.4064)
			(end -0.7874 0.4064)
			(stroke
				(width 0.1524)
				(type default)
			)
			(layer "F.SilkS")
		)
		(fp_line
			(start -0.7874 -0.4064)
			(end 0.7874 -0.4064)
			(stroke
				(width 0.1524)
				(type default)
			)
			(layer "F.SilkS")
		)
		(fp_line
			(start 0.7874 -0.4064)
			(end 0.7874 0.4064)
			(stroke
				(width 0.1524)
				(type default)
			)
			(layer "F.SilkS")
		)
		(fp_poly
			(pts
				(xy -0.508 0.2794) (xy -0.508 0.2286) (xy -0.635 0.2286) (xy -0.635 -0.254) (xy -0.5334 -0.254)
				(xy -0.5334 -0.2794) (xy 0.5334 -0.2794) (xy 0.5334 -0.254) (xy 0.635 -0.254) (xy 0.635 0.254) (xy 0.5334 0.254)
				(xy 0.5334 0.2794)
			)
			(stroke
				(width 0)
				(type default)
			)
			(fill no)
			(layer "F.CrtYd")
		)
		(pad "1" smd rect
			(at 0.40005 0 270)
			(size 0.4572 0.508)
			(layers "F.Cu" "F.Mask" "F.Paste")
			(net "SKU_PIN_BLAD2_1")
		)
		(pad "2" smd rect
			(at -0.40005 0 270)
			(size 0.4572 0.508)
			(layers "F.Cu" "F.Mask" "F.Paste")
			(net "P3V3_BLAD2")
		)
	)
	(footprint ""
		(layer "F.Cu")
		(at 338.127848 -24.038306)
		(property "Reference" "R26"
			(at -58.3438 -4.587748 0)
			(unlocked yes)
			(layer "F.SilkS")
			(effects
				(font
					(size 0.7874 0.5842)
					(thickness 0.1524)
				)
				(justify left)
			)
		)
		(property "Value" ""
			(at 0 0 0)
			(layer "F.Fab")
			(effects
				(font
					(size 1.27 1.27)
				)
			)
		)
		(duplicate_pad_numbers_are_jumpers no)
		(fp_line
			(start -0.7874 -0.4064)
			(end 0.7874 -0.4064)
			(stroke
				(width 0.1524)
				(type default)
			)
			(layer "F.SilkS")
		)
		(fp_line
			(start -0.7874 0.4064)
			(end -0.7874 -0.4064)
			(stroke
				(width 0.1524)
				(type default)
			)
			(layer "F.SilkS")
		)
		(fp_line
			(start 0.7874 -0.4064)
			(end 0.7874 0.4064)
			(stroke
				(width 0.1524)
				(type default)
			)
			(layer "F.SilkS")
		)
		(fp_line
			(start 0.7874 0.4064)
			(end -0.7874 0.4064)
			(stroke
				(width 0.1524)
				(type default)
			)
			(layer "F.SilkS")
		)
		(fp_poly
			(pts
				(xy -0.508 0.2794) (xy -0.508 0.2286) (xy -0.635 0.2286) (xy -0.635 -0.254) (xy -0.5334 -0.254)
				(xy -0.5334 -0.2794) (xy 0.5334 -0.2794) (xy 0.5334 -0.254) (xy 0.635 -0.254) (xy 0.635 0.254) (xy 0.5334 0.254)
				(xy 0.5334 0.2794)
			)
			(stroke
				(width 0)
				(type default)
			)
			(fill no)
			(layer "F.CrtYd")
		)
		(pad "1" smd rect
			(at 0.40005 0)
			(size 0.4572 0.508)
			(layers "F.Cu" "F.Mask" "F.Paste")
			(net "P3V3_BLAD2")
		)
		(pad "2" smd rect
			(at -0.40005 0)
			(size 0.4572 0.508)
			(layers "F.Cu" "F.Mask" "F.Paste")
			(net "ENET10G_4_MOD_DEF0")
		)
	)
	(footprint ""
		(layer "F.Cu")
		(at 29.029152 -26.405332 180)
		(property "Reference" "JP3"
			(at -0.488696 2.229866 0)
			(unlocked yes)
			(layer "F.SilkS")
			(effects
				(font
					(size 0.7874 0.5842)
					(thickness 0.1524)
				)
				(justify left)
			)
		)
		(property "Value" ""
			(at 0 0 180)
			(layer "F.Fab")
			(effects
				(font
					(size 1.27 1.27)
				)
			)
		)
		(duplicate_pad_numbers_are_jumpers no)
		(fp_line
			(start 2.54 1.27)
			(end -2.54 1.27)
			(stroke
				(width 0.1524)
				(type default)
			)
			(layer "F.SilkS")
		)
		(fp_line
			(start 2.54 -1.27)
			(end 2.54 1.27)
			(stroke
				(width 0.1524)
				(type default)
			)
			(layer "F.SilkS")
		)
		(fp_line
			(start -2.54 1.27)
			(end -2.54 -1.27)
			(stroke
				(width 0.1524)
				(type default)
			)
			(layer "F.SilkS")
		)
		(fp_line
			(start -2.54 -1.27)
			(end 2.54 -1.27)
			(stroke
				(width 0.1524)
				(type default)
			)
			(layer "F.SilkS")
		)
		(fp_poly
			(pts
				(xy -2.828798 0.794004) (xy -4.176014 1.314704) (xy -3.313938 2.177034)
			)
			(stroke
				(width 0)
				(type default)
			)
			(fill yes)
			(layer "F.SilkS")
		)
		(fp_poly
			(pts
				(xy -2.1082 -0.8382) (xy -2.1082 0.8382) (xy 2.1082 0.8382) (xy 2.1082 -0.8382)
			)
			(stroke
				(width 0)
				(type default)
			)
			(fill no)
			(layer "B.CrtYd")
		)
		(fp_rect
			(start -2.54 1.27)
			(end 2.54 -1.27)
			(stroke
				(width 0)
				(type default)
			)
			(fill no)
			(layer "F.CrtYd")
		)
		(fp_line
			(start 2.54 1.27)
			(end -2.54 1.27)
			(stroke
				(width 0.1)
				(type default)
			)
			(layer "F.Fab")
		)
		(fp_line
			(start 2.54 -1.27)
			(end 2.54 1.27)
			(stroke
				(width 0.1)
				(type default)
			)
			(layer "F.Fab")
		)
		(fp_line
			(start -2.54 1.27)
			(end -2.54 -1.27)
			(stroke
				(width 0.1)
				(type default)
			)
			(layer "F.Fab")
		)
		(fp_line
			(start -2.54 -1.27)
			(end 2.54 -1.27)
			(stroke
				(width 0.1)
				(type default)
			)
			(layer "F.Fab")
		)
		(fp_text user "2"
			(at 3.372104 -0.081534 0)
			(unlocked yes)
			(layer "F.SilkS")
			(effects
				(font
					(size 0.7874 0.5842)
					(thickness 0.1524)
				)
				(justify left)
			)
		)
		(fp_text user "1"
			(at -2.673096 -0.056134 0)
			(unlocked yes)
			(layer "F.SilkS")
			(effects
				(font
					(size 0.7874 0.5842)
					(thickness 0.1524)
				)
				(justify left)
			)
		)
		(fp_text user "2"
			(at 2.356104 -0.081534 0)
			(unlocked yes)
			(layer "B.SilkS")
			(effects
				(font
					(size 0.7874 0.5842)
					(thickness 0.1524)
				)
				(justify left mirror)
			)
		)
		(fp_text user "1"
			(at -2.977896 -0.056134 0)
			(unlocked yes)
			(layer "B.SilkS")
			(effects
				(font
					(size 0.7874 0.5842)
					(thickness 0.1524)
				)
				(justify left mirror)
			)
		)
		(pad "1" thru_hole rect
			(at -1.27 0 180)
			(size 1.6764 1.6764)
			(drill 1.1684)
			(layers "*.Cu" "*.Mask")
			(remove_unused_layers no)
			(net "NODE2_EN")
			(clearance 0)
			(padstack
				(mode front_inner_back)
				(layer "Inner"
					(shape circle)
					(size 1.6764 1.6764)
					(clearance 0)
				)
				(layer "B.Cu"
					(shape rect)
					(size 1.6764 1.6764)
					(clearance 0)
				)
			)
		)
		(pad "2" thru_hole circle
			(at 1.27 0 180)
			(size 1.6764 1.6764)
			(drill 1.1684)
			(layers "*.Cu" "*.Mask")
			(remove_unused_layers no)
			(net "N39386877")
			(clearance 0)
		)
	)
	(footprint ""
		(layer "F.Cu")
		(at 313.07024 -27.523694)
		(property "Reference" "R28"
			(at -6.604 -1.285748 0)
			(unlocked yes)
			(layer "F.SilkS")
			(effects
				(font
					(size 0.7874 0.5842)
					(thickness 0.1524)
				)
				(justify left)
			)
		)
		(property "Value" ""
			(at 0 0 0)
			(layer "F.Fab")
			(effects
				(font
					(size 1.27 1.27)
				)
			)
		)
		(duplicate_pad_numbers_are_jumpers no)
		(fp_line
			(start -0.7874 -0.4064)
			(end 0.7874 -0.4064)
			(stroke
				(width 0.1524)
				(type default)
			)
			(layer "F.SilkS")
		)
		(fp_line
			(start -0.7874 0.4064)
			(end -0.7874 -0.4064)
			(stroke
				(width 0.1524)
				(type default)
			)
			(layer "F.SilkS")
		)
		(fp_line
			(start 0.7874 -0.4064)
			(end 0.7874 0.4064)
			(stroke
				(width 0.1524)
				(type default)
			)
			(layer "F.SilkS")
		)
		(fp_line
			(start 0.7874 0.4064)
			(end -0.7874 0.4064)
			(stroke
				(width 0.1524)
				(type default)
			)
			(layer "F.SilkS")
		)
		(fp_poly
			(pts
				(xy -0.508 0.2794) (xy -0.508 0.2286) (xy -0.635 0.2286) (xy -0.635 -0.254) (xy -0.5334 -0.254)
				(xy -0.5334 -0.2794) (xy 0.5334 -0.2794) (xy 0.5334 -0.254) (xy 0.635 -0.254) (xy 0.635 0.254) (xy 0.5334 0.254)
				(xy 0.5334 0.2794)
			)
			(stroke
				(width 0)
				(type default)
			)
			(fill no)
			(layer "F.CrtYd")
		)
		(pad "1" smd rect
			(at 0.40005 0)
			(size 0.4572 0.508)
			(layers "F.Cu" "F.Mask" "F.Paste")
			(net "P3V3_BLAD2")
		)
		(pad "2" smd rect
			(at -0.40005 0)
			(size 0.4572 0.508)
			(layers "F.Cu" "F.Mask" "F.Paste")
			(net "ENET10G_4_RS0")
		)
	)
	(footprint ""
		(layer "F.Cu")
		(at 306.324 -33.655 90)
		(property "Reference" "L8"
			(at -0.9906 -2.79273 90)
			(unlocked yes)
			(layer "F.SilkS")
			(effects
				(font
					(size 0.7874 0.5842)
					(thickness 0.1524)
				)
				(justify left)
			)
		)
		(property "Value" ""
			(at 0 0 90)
			(layer "F.Fab")
			(effects
				(font
					(size 1.27 1.27)
				)
			)
		)
		(duplicate_pad_numbers_are_jumpers no)
		(fp_line
			(start -1.905 -0.8636)
			(end 1.905 -0.8636)
			(stroke
				(width 0.1524)
				(type default)
			)
			(layer "F.SilkS")
		)
		(fp_line
			(start 1.905 0.8382)
			(end 1.905 -0.8382)
			(stroke
				(width 0.1524)
				(type default)
			)
			(layer "F.SilkS")
		)
		(fp_line
			(start 0.127 0.8382)
			(end 0.127 -0.8382)
			(stroke
				(width 0.1524)
				(type default)
			)
			(layer "F.SilkS")
		)
		(fp_line
			(start -0.127 0.8382)
			(end -0.127 -0.8382)
			(stroke
				(width 0.1524)
				(type default)
			)
			(layer "F.SilkS")
		)
		(fp_line
			(start -1.905 0.8382)
			(end -1.905 -0.8382)
			(stroke
				(width 0.1524)
				(type default)
			)
			(layer "F.SilkS")
		)
		(fp_line
			(start 1.905 0.8636)
			(end -1.905 0.8636)
			(stroke
				(width 0.1524)
				(type default)
			)
			(layer "F.SilkS")
		)
		(fp_rect
			(start -1.524 0.7112)
			(end 1.524 -0.7366)
			(stroke
				(width 0)
				(type default)
			)
			(fill no)
			(layer "F.CrtYd")
		)
		(pad "1" smd rect
			(at 0.94996 0 90)
			(size 1.1176 1.3716)
			(layers "F.Cu" "F.Mask" "F.Paste")
			(net "P3V3_10G_4_VCCR_L")
		)
		(pad "2" smd rect
			(at -0.94996 0 90)
			(size 1.1176 1.3716)
			(layers "F.Cu" "F.Mask" "F.Paste")
			(net "P3V3_10G_4_VCCR")
		)
	)
	(footprint ""
		(layer "F.Cu")
		(at 4.499864 -28.999942 180)
		(property "Reference" "H5"
			(at -0.245872 10.900664 0)
			(unlocked yes)
			(layer "F.SilkS")
			(effects
				(font
					(size 0.7874 0.5842)
					(thickness 0.1524)
				)
				(justify left)
			)
		)
		(property "Value" ""
			(at 0 0 180)
			(layer "F.Fab")
			(effects
				(font
					(size 1.27 1.27)
				)
			)
		)
		(duplicate_pad_numbers_are_jumpers no)
		(fp_poly
			(pts
				(arc
					(start 3.999992 5.999988)
					(mid 0 9.99998)
					(end -3.999992 5.999988)
				)
				(arc
					(start -3.999992 0)
					(mid 0 -3.999992)
					(end 3.999992 0)
				)
			)
			(stroke
				(width 0)
				(type default)
			)
			(fill no)
			(layer "B.CrtYd")
		)
		(fp_poly
			(pts
				(arc
					(start 3.999992 5.999988)
					(mid 0 9.99998)
					(end -3.999992 5.999988)
				)
				(arc
					(start -3.999992 0)
					(mid 0 -3.999992)
					(end 3.999992 0)
				)
			)
			(stroke
				(width 0)
				(type default)
			)
			(fill no)
			(layer "F.CrtYd")
		)
		(pad "" np_thru_hole circle
			(at 0 0 180)
			(size 3.5052 3.5052)
			(drill 3.5052)
			(layers "*.Cu" "*.Mask")
			(clearance 0.381)
			(thermal_gap 0.381)
		)
		(zone
			(layers "F.Cu" "B.Cu" "In1.Cu" "In2.Cu" "In3.Cu" "In4.Cu" "In5.Cu" "In6.Cu")
			(hatch none 0.5)
			(connect_pads
				(clearance 0)
			)
			(min_thickness 0.25)
			(keepout
				(tracks not_allowed)
				(vias allowed)
				(pads allowed)
				(copperpour not_allowed)
				(footprints allowed)
			)
			(placement
				(enabled no)
				(sheetname "")
			)
			(fill
				(thermal_gap 0.5)
				(thermal_bridge_width 0.5)
				(island_removal_mode 0)
			)
			(polygon
				(pts
					(arc
						(start 2.088134 -32.452564)
						(mid 4.499864 -38.507852)
						(end 6.911594 -32.452564)
					)
					(arc
						(start 6.911594 -32.452564)
						(mid 6.797965 -32.289703)
						(end 6.757924 -32.095186)
					)
					(arc
						(start 6.757924 -28.999942)
						(mid 4.499864 -26.741882)
						(end 2.241804 -28.999942)
					)
					(arc
						(start 2.241804 -32.095186)
						(mid 2.201818 -32.289726)
						(end 2.088134 -32.452564)
					)
				)
			)
		)
	)
)
